(kicad_pcb
	(version 20260206)
	(generator "pcbnew")
	(generator_version "10.0")
	(general
		(thickness 1.6)
		(legacy_teardrops no)
	)
	(paper "A4")
	(title_block
		(title "04192023_DAF0TMB3IC0_F0TG_MB_C_brd_V02_OCP.brd")
		(comment 1 "Grand Teton / footprint 230 of 8354 (J100), pads 114-226 of 291")
	)
	(layers
		(0 "F.Cu" signal "TOP")
		(4 "In1.Cu" signal "GND")
		(6 "In2.Cu" signal "IN1")
		(8 "In3.Cu" signal "GND1")
		(10 "In4.Cu" signal "IN2")
		(12 "In5.Cu" signal "GND2")
		(14 "In6.Cu" signal "IN3")
		(16 "In7.Cu" signal "GND3")
		(18 "In8.Cu" signal "VCC")
		(20 "In9.Cu" signal "VCC1")
		(22 "In10.Cu" signal "GND4")
		(24 "In11.Cu" signal "IN4")
		(26 "In12.Cu" signal "GND5")
		(28 "In13.Cu" signal "IN5")
		(30 "In14.Cu" signal "GND6")
		(32 "In15.Cu" signal "IN6")
		(34 "In16.Cu" signal "GND7")
		(2 "B.Cu" signal "BOTTOM")
		(9 "F.Adhes" user "F.Adhesive")
		(11 "B.Adhes" user "B.Adhesive")
		(13 "F.Paste" user "Package Geometry/Pastemask Top")
		(15 "B.Paste" user "Package Geometry/Pastemask Bottom")
		(5 "F.SilkS" user "Ref Des/Silkscreen Top")
		(7 "B.SilkS" user "Ref Des/Silkscreen Bottom")
		(1 "F.Mask" user "Board Geometry/Soldermask Top")
		(3 "B.Mask" user "Board Geometry/Soldermask Bottom")
		(17 "Dwgs.User" user "User.Drawings")
		(19 "Cmts.User" user "User.Comments")
		(21 "Eco1.User" user "User.Eco1")
		(23 "Eco2.User" user "User.Eco2")
		(25 "Edge.Cuts" user "Board Geometry/Outline")
		(27 "Margin" user)
		(31 "F.CrtYd" user "Package Geometry/Place Bound Top")
		(29 "B.CrtYd" user "Package Geometry/Place Bound Bottom")
		(35 "F.Fab" user "Ref Des/Assembly Top")
		(33 "B.Fab" user "Ref Des/Assembly Bottom")
	)
	(footprint ""
		(layer "F.Cu")
		(at 181.566058 -255.560322 180)
		(property "Reference" "J100"
			(at -2.7178 -81.857088 0)
			(unlocked yes)
			(layer "F.SilkS")
			(effects
				(font
					(size 0.7874 0.5842)
					(thickness 0.1524)
				)
			)
		)
		(property "Value" ""
			(at 0 0 180)
			(layer "F.Fab")
			(effects
				(font
					(size 1.27 1.27)
				)
			)
		)
		(duplicate_pad_numbers_are_jumpers no)
		(pad "114" smd rect
			(at -2.050034 37.824918 90)
			(size 0.519938 1.4986)
			(layers "F.Cu" "F.Mask" "F.Paste")
			(net "GND")
		)
		(pad "115" smd rect
			(at -2.050034 38.675056 90)
			(size 0.519938 1.4986)
			(layers "F.Cu" "F.Mask" "F.Paste")
			(net "M_I_CPU1_SB_DQS_DP<1>")
		)
		(pad "116" smd rect
			(at -2.050034 39.52494 90)
			(size 0.519938 1.4986)
			(layers "F.Cu" "F.Mask" "F.Paste")
			(net "M_I_CPU1_SB_DQS_DN<1>")
		)
		(pad "117" smd rect
			(at -2.050034 40.375078 90)
			(size 0.519938 1.4986)
			(layers "F.Cu" "F.Mask" "F.Paste")
			(net "GND")
		)
		(pad "118" smd rect
			(at -2.050034 41.224962 90)
			(size 0.519938 1.4986)
			(layers "F.Cu" "F.Mask" "F.Paste")
			(net "M_I_CPU1_SB_DQ<12>")
		)
		(pad "119" smd rect
			(at -2.050034 42.0751 90)
			(size 0.519938 1.4986)
			(layers "F.Cu" "F.Mask" "F.Paste")
			(net "GND")
		)
		(pad "120" smd rect
			(at -2.050034 42.924984 90)
			(size 0.519938 1.4986)
			(layers "F.Cu" "F.Mask" "F.Paste")
			(net "M_I_CPU1_SB_DQ<13>")
		)
		(pad "121" smd rect
			(at -2.050034 43.775122 90)
			(size 0.519938 1.4986)
			(layers "F.Cu" "F.Mask" "F.Paste")
			(net "GND")
		)
		(pad "122" smd rect
			(at -2.050034 44.625006 90)
			(size 0.519938 1.4986)
			(layers "F.Cu" "F.Mask" "F.Paste")
			(net "M_I_CPU1_SB_DQ<16>")
		)
		(pad "123" smd rect
			(at -2.050034 45.47489 90)
			(size 0.519938 1.4986)
			(layers "F.Cu" "F.Mask" "F.Paste")
			(net "GND")
		)
		(pad "124" smd rect
			(at -2.050034 46.325028 90)
			(size 0.519938 1.4986)
			(layers "F.Cu" "F.Mask" "F.Paste")
			(net "M_I_CPU1_SB_DQ<17>")
		)
		(pad "125" smd rect
			(at -2.050034 47.174912 90)
			(size 0.519938 1.4986)
			(layers "F.Cu" "F.Mask" "F.Paste")
			(net "GND")
		)
		(pad "126" smd rect
			(at -2.050034 48.02505 90)
			(size 0.519938 1.4986)
			(layers "F.Cu" "F.Mask" "F.Paste")
			(net "M_I_CPU1_SB_DQS_DP<2>")
		)
		(pad "127" smd rect
			(at -2.050034 48.874934 90)
			(size 0.519938 1.4986)
			(layers "F.Cu" "F.Mask" "F.Paste")
			(net "M_I_CPU1_SB_DQS_DN<2>")
		)
		(pad "128" smd rect
			(at -2.050034 49.725072 90)
			(size 0.519938 1.4986)
			(layers "F.Cu" "F.Mask" "F.Paste")
			(net "GND")
		)
		(pad "129" smd rect
			(at -2.050034 50.574956 90)
			(size 0.519938 1.4986)
			(layers "F.Cu" "F.Mask" "F.Paste")
			(net "M_I_CPU1_SB_DQ<20>")
		)
		(pad "130" smd rect
			(at -2.050034 51.425094 90)
			(size 0.519938 1.4986)
			(layers "F.Cu" "F.Mask" "F.Paste")
			(net "GND")
		)
		(pad "131" smd rect
			(at -2.050034 52.274978 90)
			(size 0.519938 1.4986)
			(layers "F.Cu" "F.Mask" "F.Paste")
			(net "M_I_CPU1_SB_DQ<21>")
		)
		(pad "132" smd rect
			(at -2.050034 53.125116 90)
			(size 0.519938 1.4986)
			(layers "F.Cu" "F.Mask" "F.Paste")
			(net "GND")
		)
		(pad "133" smd rect
			(at -2.050034 53.975 90)
			(size 0.519938 1.4986)
			(layers "F.Cu" "F.Mask" "F.Paste")
			(net "M_I_CPU1_SB_DQ<24>")
		)
		(pad "134" smd rect
			(at -2.050034 54.824884 90)
			(size 0.519938 1.4986)
			(layers "F.Cu" "F.Mask" "F.Paste")
			(net "GND")
		)
		(pad "135" smd rect
			(at -2.050034 55.675022 90)
			(size 0.519938 1.4986)
			(layers "F.Cu" "F.Mask" "F.Paste")
			(net "M_I_CPU1_SB_DQ<25>")
		)
		(pad "136" smd rect
			(at -2.050034 56.524906 90)
			(size 0.519938 1.4986)
			(layers "F.Cu" "F.Mask" "F.Paste")
			(net "GND")
		)
		(pad "137" smd rect
			(at -2.050034 57.375044 90)
			(size 0.519938 1.4986)
			(layers "F.Cu" "F.Mask" "F.Paste")
			(net "M_I_CPU1_SB_DQS_DP<3>")
		)
		(pad "138" smd rect
			(at -2.050034 58.224928 90)
			(size 0.519938 1.4986)
			(layers "F.Cu" "F.Mask" "F.Paste")
			(net "M_I_CPU1_SB_DQS_DN<3>")
		)
		(pad "139" smd rect
			(at -2.050034 59.075066 90)
			(size 0.519938 1.4986)
			(layers "F.Cu" "F.Mask" "F.Paste")
			(net "GND")
		)
		(pad "140" smd rect
			(at -2.050034 59.92495 90)
			(size 0.519938 1.4986)
			(layers "F.Cu" "F.Mask" "F.Paste")
			(net "M_I_CPU1_SB_DQ<28>")
		)
		(pad "141" smd rect
			(at -2.050034 60.775088 90)
			(size 0.519938 1.4986)
			(layers "F.Cu" "F.Mask" "F.Paste")
			(net "GND")
		)
		(pad "142" smd rect
			(at -2.050034 61.624972 90)
			(size 0.519938 1.4986)
			(layers "F.Cu" "F.Mask" "F.Paste")
			(net "M_I_CPU1_SB_DQ<29>")
		)
		(pad "143" smd rect
			(at -2.050034 62.47511 90)
			(size 0.519938 1.4986)
			(layers "F.Cu" "F.Mask" "F.Paste")
			(net "GND")
		)
		(pad "144" smd rect
			(at -2.050034 63.324994 90)
			(size 0.519938 1.4986)
			(layers "F.Cu" "F.Mask" "F.Paste")
			(net "Net_2369")
		)
		(pad "145" smd rect
			(at 2.050034 -63.324994 90)
			(size 0.519938 1.4986)
			(layers "F.Cu" "F.Mask" "F.Paste")
			(net "P12V_MEM_CPU1")
		)
		(pad "146" smd rect
			(at 2.050034 -62.47511 90)
			(size 0.519938 1.4986)
			(layers "F.Cu" "F.Mask" "F.Paste")
			(net "P12V_MEM_CPU1")
		)
		(pad "147" smd rect
			(at 2.050034 -61.624972 90)
			(size 0.519938 1.4986)
			(layers "F.Cu" "F.Mask" "F.Paste")
			(net "PWRGD_CHI_CPU1_DIMM")
		)
		(pad "148" smd rect
			(at 2.050034 -60.775088 90)
			(size 0.519938 1.4986)
			(layers "F.Cu" "F.Mask" "F.Paste")
			(net "PD_CHI_CPU1_DIMM_SAA")
		)
		(pad "149" smd rect
			(at 2.050034 -59.92495 90)
			(size 0.519938 1.4986)
			(layers "F.Cu" "F.Mask" "F.Paste")
			(net "Net_2370")
		)
		(pad "150" smd rect
			(at 2.050034 -59.075066 90)
			(size 0.519938 1.4986)
			(layers "F.Cu" "F.Mask" "F.Paste")
			(net "Net_2371")
		)
		(pad "151" smd rect
			(at 2.050034 -58.224928 90)
			(size 0.519938 1.4986)
			(layers "F.Cu" "F.Mask" "F.Paste")
			(net "GND")
		)
		(pad "152" smd rect
			(at 2.050034 -57.375044 90)
			(size 0.519938 1.4986)
			(layers "F.Cu" "F.Mask" "F.Paste")
			(net "M_I_CPU1_SA_DQ<2>")
		)
		(pad "153" smd rect
			(at 2.050034 -56.524906 90)
			(size 0.519938 1.4986)
			(layers "F.Cu" "F.Mask" "F.Paste")
			(net "GND")
		)
		(pad "154" smd rect
			(at 2.050034 -55.675022 90)
			(size 0.519938 1.4986)
			(layers "F.Cu" "F.Mask" "F.Paste")
			(net "M_I_CPU1_SA_DQ<3>")
		)
		(pad "155" smd rect
			(at 2.050034 -54.824884 90)
			(size 0.519938 1.4986)
			(layers "F.Cu" "F.Mask" "F.Paste")
			(net "GND")
		)
		(pad "156" smd rect
			(at 2.050034 -53.975 90)
			(size 0.519938 1.4986)
			(layers "F.Cu" "F.Mask" "F.Paste")
			(net "M_I_CPU1_SA_DQS_DN<5>")
		)
		(pad "157" smd rect
			(at 2.050034 -53.125116 90)
			(size 0.519938 1.4986)
			(layers "F.Cu" "F.Mask" "F.Paste")
			(net "M_I_CPU1_SA_DQS_DP<5>")
		)
		(pad "158" smd rect
			(at 2.050034 -52.274978 90)
			(size 0.519938 1.4986)
			(layers "F.Cu" "F.Mask" "F.Paste")
			(net "GND")
		)
		(pad "159" smd rect
			(at 2.050034 -51.425094 90)
			(size 0.519938 1.4986)
			(layers "F.Cu" "F.Mask" "F.Paste")
			(net "M_I_CPU1_SA_DQ<6>")
		)
		(pad "160" smd rect
			(at 2.050034 -50.574956 90)
			(size 0.519938 1.4986)
			(layers "F.Cu" "F.Mask" "F.Paste")
			(net "GND")
		)
		(pad "161" smd rect
			(at 2.050034 -49.725072 90)
			(size 0.519938 1.4986)
			(layers "F.Cu" "F.Mask" "F.Paste")
			(net "M_I_CPU1_SA_DQ<7>")
		)
		(pad "162" smd rect
			(at 2.050034 -48.874934 90)
			(size 0.519938 1.4986)
			(layers "F.Cu" "F.Mask" "F.Paste")
			(net "GND")
		)
		(pad "163" smd rect
			(at 2.050034 -48.02505 90)
			(size 0.519938 1.4986)
			(layers "F.Cu" "F.Mask" "F.Paste")
			(net "M_I_CPU1_SA_DQ<10>")
		)
		(pad "164" smd rect
			(at 2.050034 -47.174912 90)
			(size 0.519938 1.4986)
			(layers "F.Cu" "F.Mask" "F.Paste")
			(net "GND")
		)
		(pad "165" smd rect
			(at 2.050034 -46.325028 90)
			(size 0.519938 1.4986)
			(layers "F.Cu" "F.Mask" "F.Paste")
			(net "M_I_CPU1_SA_DQ<11>")
		)
		(pad "166" smd rect
			(at 2.050034 -45.47489 90)
			(size 0.519938 1.4986)
			(layers "F.Cu" "F.Mask" "F.Paste")
			(net "GND")
		)
		(pad "167" smd rect
			(at 2.050034 -44.625006 90)
			(size 0.519938 1.4986)
			(layers "F.Cu" "F.Mask" "F.Paste")
			(net "M_I_CPU1_SA_DQS_DN<6>")
		)
		(pad "168" smd rect
			(at 2.050034 -43.775122 90)
			(size 0.519938 1.4986)
			(layers "F.Cu" "F.Mask" "F.Paste")
			(net "M_I_CPU1_SA_DQS_DP<6>")
		)
		(pad "169" smd rect
			(at 2.050034 -42.924984 90)
			(size 0.519938 1.4986)
			(layers "F.Cu" "F.Mask" "F.Paste")
			(net "GND")
		)
		(pad "170" smd rect
			(at 2.050034 -42.0751 90)
			(size 0.519938 1.4986)
			(layers "F.Cu" "F.Mask" "F.Paste")
			(net "M_I_CPU1_SA_DQ<14>")
		)
		(pad "171" smd rect
			(at 2.050034 -41.224962 90)
			(size 0.519938 1.4986)
			(layers "F.Cu" "F.Mask" "F.Paste")
			(net "GND")
		)
		(pad "172" smd rect
			(at 2.050034 -40.375078 90)
			(size 0.519938 1.4986)
			(layers "F.Cu" "F.Mask" "F.Paste")
			(net "M_I_CPU1_SA_DQ<15>")
		)
		(pad "173" smd rect
			(at 2.050034 -39.52494 90)
			(size 0.519938 1.4986)
			(layers "F.Cu" "F.Mask" "F.Paste")
			(net "GND")
		)
		(pad "174" smd rect
			(at 2.050034 -38.675056 90)
			(size 0.519938 1.4986)
			(layers "F.Cu" "F.Mask" "F.Paste")
			(net "M_I_CPU1_SA_DQ<18>")
		)
		(pad "175" smd rect
			(at 2.050034 -37.824918 90)
			(size 0.519938 1.4986)
			(layers "F.Cu" "F.Mask" "F.Paste")
			(net "GND")
		)
		(pad "176" smd rect
			(at 2.050034 -36.975034 90)
			(size 0.519938 1.4986)
			(layers "F.Cu" "F.Mask" "F.Paste")
			(net "M_I_CPU1_SA_DQ<19>")
		)
		(pad "177" smd rect
			(at 2.050034 -36.124896 90)
			(size 0.519938 1.4986)
			(layers "F.Cu" "F.Mask" "F.Paste")
			(net "GND")
		)
		(pad "178" smd rect
			(at 2.050034 -35.275012 90)
			(size 0.519938 1.4986)
			(layers "F.Cu" "F.Mask" "F.Paste")
			(net "M_I_CPU1_SA_DQS_DN<7>")
		)
		(pad "179" smd rect
			(at 2.050034 -34.425128 90)
			(size 0.519938 1.4986)
			(layers "F.Cu" "F.Mask" "F.Paste")
			(net "M_I_CPU1_SA_DQS_DP<7>")
		)
		(pad "180" smd rect
			(at 2.050034 -33.57499 90)
			(size 0.519938 1.4986)
			(layers "F.Cu" "F.Mask" "F.Paste")
			(net "GND")
		)
		(pad "181" smd rect
			(at 2.050034 -32.725106 90)
			(size 0.519938 1.4986)
			(layers "F.Cu" "F.Mask" "F.Paste")
			(net "M_I_CPU1_SA_DQ<22>")
		)
		(pad "182" smd rect
			(at 2.050034 -31.874968 90)
			(size 0.519938 1.4986)
			(layers "F.Cu" "F.Mask" "F.Paste")
			(net "GND")
		)
		(pad "183" smd rect
			(at 2.050034 -31.025084 90)
			(size 0.519938 1.4986)
			(layers "F.Cu" "F.Mask" "F.Paste")
			(net "M_I_CPU1_SA_DQ<23>")
		)
		(pad "184" smd rect
			(at 2.050034 -30.174946 90)
			(size 0.519938 1.4986)
			(layers "F.Cu" "F.Mask" "F.Paste")
			(net "GND")
		)
		(pad "185" smd rect
			(at 2.050034 -29.325062 90)
			(size 0.519938 1.4986)
			(layers "F.Cu" "F.Mask" "F.Paste")
			(net "M_I_CPU1_SA_DQ<26>")
		)
		(pad "186" smd rect
			(at 2.050034 -28.474924 90)
			(size 0.519938 1.4986)
			(layers "F.Cu" "F.Mask" "F.Paste")
			(net "GND")
		)
		(pad "187" smd rect
			(at 2.050034 -27.62504 90)
			(size 0.519938 1.4986)
			(layers "F.Cu" "F.Mask" "F.Paste")
			(net "M_I_CPU1_SA_DQ<27>")
		)
		(pad "188" smd rect
			(at 2.050034 -26.774902 90)
			(size 0.519938 1.4986)
			(layers "F.Cu" "F.Mask" "F.Paste")
			(net "GND")
		)
		(pad "189" smd rect
			(at 2.050034 -25.925018 90)
			(size 0.519938 1.4986)
			(layers "F.Cu" "F.Mask" "F.Paste")
			(net "M_I_CPU1_SA_DQS_DN<8>")
		)
		(pad "190" smd rect
			(at 2.050034 -25.07488 90)
			(size 0.519938 1.4986)
			(layers "F.Cu" "F.Mask" "F.Paste")
			(net "M_I_CPU1_SA_DQS_DP<8>")
		)
		(pad "191" smd rect
			(at 2.050034 -24.224996 90)
			(size 0.519938 1.4986)
			(layers "F.Cu" "F.Mask" "F.Paste")
			(net "GND")
		)
		(pad "192" smd rect
			(at 2.050034 -23.375112 90)
			(size 0.519938 1.4986)
			(layers "F.Cu" "F.Mask" "F.Paste")
			(net "M_I_CPU1_SA_DQ<30>")
		)
		(pad "193" smd rect
			(at 2.050034 -22.524974 90)
			(size 0.519938 1.4986)
			(layers "F.Cu" "F.Mask" "F.Paste")
			(net "GND")
		)
		(pad "194" smd rect
			(at 2.050034 -21.67509 90)
			(size 0.519938 1.4986)
			(layers "F.Cu" "F.Mask" "F.Paste")
			(net "M_I_CPU1_SA_DQ<31>")
		)
		(pad "195" smd rect
			(at 2.050034 -20.824952 90)
			(size 0.519938 1.4986)
			(layers "F.Cu" "F.Mask" "F.Paste")
			(net "GND")
		)
		(pad "196" smd rect
			(at 2.050034 -19.975068 90)
			(size 0.519938 1.4986)
			(layers "F.Cu" "F.Mask" "F.Paste")
			(net "M_I_CPU1_SA_CB<2>")
		)
		(pad "197" smd rect
			(at 2.050034 -19.12493 90)
			(size 0.519938 1.4986)
			(layers "F.Cu" "F.Mask" "F.Paste")
			(net "GND")
		)
		(pad "198" smd rect
			(at 2.050034 -18.275046 90)
			(size 0.519938 1.4986)
			(layers "F.Cu" "F.Mask" "F.Paste")
			(net "M_I_CPU1_SA_CB<3>")
		)
		(pad "199" smd rect
			(at 2.050034 -17.424908 90)
			(size 0.519938 1.4986)
			(layers "F.Cu" "F.Mask" "F.Paste")
			(net "GND")
		)
		(pad "200" smd rect
			(at 2.050034 -16.575024 90)
			(size 0.519938 1.4986)
			(layers "F.Cu" "F.Mask" "F.Paste")
			(net "M_I_CPU1_SA_DQS_DN<9>")
		)
		(pad "201" smd rect
			(at 2.050034 -15.724886 90)
			(size 0.519938 1.4986)
			(layers "F.Cu" "F.Mask" "F.Paste")
			(net "M_I_CPU1_SA_DQS_DP<9>")
		)
		(pad "202" smd rect
			(at 2.050034 -14.875002 90)
			(size 0.519938 1.4986)
			(layers "F.Cu" "F.Mask" "F.Paste")
			(net "GND")
		)
		(pad "203" smd rect
			(at 2.050034 -14.025118 90)
			(size 0.519938 1.4986)
			(layers "F.Cu" "F.Mask" "F.Paste")
			(net "M_I_CPU1_SA_CB<6>")
		)
		(pad "204" smd rect
			(at 2.050034 -13.17498 90)
			(size 0.519938 1.4986)
			(layers "F.Cu" "F.Mask" "F.Paste")
			(net "GND")
		)
		(pad "205" smd rect
			(at 2.050034 -12.325096 90)
			(size 0.519938 1.4986)
			(layers "F.Cu" "F.Mask" "F.Paste")
			(net "M_I_CPU1_SA_CB<7>")
		)
		(pad "206" smd rect
			(at 2.050034 -11.474958 90)
			(size 0.519938 1.4986)
			(layers "F.Cu" "F.Mask" "F.Paste")
			(net "GND")
		)
		(pad "207" smd rect
			(at 2.050034 -10.625074 90)
			(size 0.519938 1.4986)
			(layers "F.Cu" "F.Mask" "F.Paste")
			(net "M_I_CPU1_RESET_N")
		)
		(pad "208" smd rect
			(at 2.050034 -9.774936 90)
			(size 0.519938 1.4986)
			(layers "F.Cu" "F.Mask" "F.Paste")
			(net "GND")
		)
		(pad "209" smd rect
			(at 2.050034 -8.925052 90)
			(size 0.519938 1.4986)
			(layers "F.Cu" "F.Mask" "F.Paste")
			(net "M_I_CPU1_SA_CS_N<1>")
		)
		(pad "210" smd rect
			(at 2.050034 -8.074914 90)
			(size 0.519938 1.4986)
			(layers "F.Cu" "F.Mask" "F.Paste")
			(net "GND")
		)
		(pad "211" smd rect
			(at 2.050034 -7.22503 90)
			(size 0.519938 1.4986)
			(layers "F.Cu" "F.Mask" "F.Paste")
			(net "M_I_CPU1_SA_CA<1>")
		)
		(pad "212" smd rect
			(at 2.050034 -6.374892 90)
			(size 0.519938 1.4986)
			(layers "F.Cu" "F.Mask" "F.Paste")
			(net "GND")
		)
		(pad "213" smd rect
			(at 2.050034 -5.525008 90)
			(size 0.519938 1.4986)
			(layers "F.Cu" "F.Mask" "F.Paste")
			(net "M_I_CPU1_SA_CA<3>")
		)
		(pad "214" smd rect
			(at 2.050034 -4.675124 90)
			(size 0.519938 1.4986)
			(layers "F.Cu" "F.Mask" "F.Paste")
			(net "GND")
		)
		(pad "215" smd rect
			(at 2.050034 -3.824986 90)
			(size 0.519938 1.4986)
			(layers "F.Cu" "F.Mask" "F.Paste")
			(net "M_I_CPU1_SA_CA<5>")
		)
		(pad "216" smd rect
			(at 2.050034 -2.975102 90)
			(size 0.519938 1.4986)
			(layers "F.Cu" "F.Mask" "F.Paste")
			(net "GND")
		)
		(pad "217" smd rect
			(at 2.050034 -2.124964 90)
			(size 0.519938 1.4986)
			(layers "F.Cu" "F.Mask" "F.Paste")
			(net "M_I_CPU1_CLK_DP<0>")
		)
		(pad "218" smd rect
			(at 2.050034 -1.27508 90)
			(size 0.519938 1.4986)
			(layers "F.Cu" "F.Mask" "F.Paste")
			(net "M_I_CPU1_CLK_DN<0>")
		)
		(pad "219" smd rect
			(at 2.050034 -0.424942 90)
			(size 0.519938 1.4986)
			(layers "F.Cu" "F.Mask" "F.Paste")
			(net "GND")
		)
		(pad "220" smd rect
			(at 2.050034 5.525008 90)
			(size 0.519938 1.4986)
			(layers "F.Cu" "F.Mask" "F.Paste")
			(net "Net_2372")
		)
		(pad "221" smd rect
			(at 2.050034 6.374892 90)
			(size 0.519938 1.4986)
			(layers "F.Cu" "F.Mask" "F.Paste")
			(net "M_I_CPU1_SB_CA<1>")
		)
		(pad "222" smd rect
			(at 2.050034 7.22503 90)
			(size 0.519938 1.4986)
			(layers "F.Cu" "F.Mask" "F.Paste")
			(net "GND")
		)
		(pad "223" smd rect
			(at 2.050034 8.074914 90)
			(size 0.519938 1.4986)
			(layers "F.Cu" "F.Mask" "F.Paste")
			(net "M_I_CPU1_SB_CA<3>")
		)
		(pad "224" smd rect
			(at 2.050034 8.925052 90)
			(size 0.519938 1.4986)
			(layers "F.Cu" "F.Mask" "F.Paste")
			(net "GND")
		)
		(pad "225" smd rect
			(at 2.050034 9.774936 90)
			(size 0.519938 1.4986)
			(layers "F.Cu" "F.Mask" "F.Paste")
			(net "M_I_CPU1_SB_CA<5>")
		)
		(pad "226" smd rect
			(at 2.050034 10.625074 90)
			(size 0.519938 1.4986)
			(layers "F.Cu" "F.Mask" "F.Paste")
			(net "GND")
		)
	)
)
